(kicad_pcb
	(version 20260206)
	(generator "pcbnew")
	(generator_version "10.0")
	(general
		(thickness 1.6)
		(legacy_teardrops no)
	)
	(paper "A4")
	(title_block
		(title "timecard-production-celestica-r4006 — R4006-B0001-02_R01.brd")
		(comment 1 "Time Appliance Project (Time Card) / footprints 14-17 of 1113")
	)
	(layers
		(0 "F.Cu" signal "TOP")
		(4 "In1.Cu" signal "L02_GND1")
		(6 "In2.Cu" signal "L03_SIG1")
		(8 "In3.Cu" signal "L04_GND2")
		(10 "In4.Cu" signal "L05_VCC1")
		(12 "In5.Cu" signal "L06_VCC2")
		(14 "In6.Cu" signal "L07_GND3")
		(16 "In7.Cu" signal "L08_SIG2")
		(18 "In8.Cu" signal "L09_GND4")
		(2 "B.Cu" signal "BOTTOM")
		(9 "F.Adhes" user "F.Adhesive")
		(11 "B.Adhes" user "B.Adhesive")
		(13 "F.Paste" user "Package Geometry/Pastemask Top")
		(15 "B.Paste" user "Package Geometry/Pastemask Bottom")
		(5 "F.SilkS" user "Ref Des/Silkscreen Top")
		(7 "B.SilkS" user "Ref Des/Silkscreen Bottom")
		(1 "F.Mask" user "Board Geometry/Soldermask Top")
		(3 "B.Mask" user "Board Geometry/Soldermask Bottom")
		(17 "Dwgs.User" user "User.Drawings")
		(19 "Cmts.User" user "User.Comments")
		(21 "Eco1.User" user "User.Eco1")
		(23 "Eco2.User" user "User.Eco2")
		(25 "Edge.Cuts" user "Board Geometry/Outline")
		(27 "Margin" user)
		(31 "F.CrtYd" user "Package Geometry/Place Bound Top")
		(29 "B.CrtYd" user "Package Geometry/Place Bound Bottom")
		(35 "F.Fab" user "Ref Des/Assembly Top")
		(33 "B.Fab" user "Ref Des/Assembly Bottom")
	)
	(footprint ""
		(layer "F.Cu")
		(at 115.189 -59.563 90)
		(property "Reference" "R238"
			(at -0.635 -1.86563 90)
			(unlocked yes)
			(layer "F.SilkS")
			(effects
				(font
					(size 0.7874 0.5842)
					(thickness 0.1524)
				)
			)
		)
		(property "Value" "VAL*"
			(at 0.02032 2.13233 90)
			(unlocked yes)
			(layer "F.Fab")
			(hide yes)
			(effects
				(font
					(size 0.7874 0.5842)
					(thickness 0.1524)
				)
			)
		)
		(property "Tolerance" "TOL*"
			(at 0.044704 3.05435 90)
			(unlocked yes)
			(layer "Cmts.User")
			(hide yes)
			(effects
				(font
					(size 0.7874 0.5842)
					(thickness 0.1524)
				)
			)
		)
		(property "User Part Number" "PARTNUM*"
			(at 0.02032 4.024884 90)
			(unlocked yes)
			(layer "Cmts.User")
			(hide yes)
			(effects
				(font
					(size 0.7874 0.5842)
					(thickness 0.1524)
				)
			)
		)
		(property "Device Type" "RESISTOR-G155-133R0-01,33OHM,1%"
			(at 0.008382 1.210564 90)
			(unlocked yes)
			(layer "F.Fab")
			(hide yes)
			(effects
				(font
					(size 0.7874 0.5842)
					(thickness 0.1524)
				)
			)
		)
		(duplicate_pad_numbers_are_jumpers no)
		(fp_line
			(start 1.143 -0.5588)
			(end -1.143 -0.5588)
			(stroke
				(width 0.1)
				(type default)
			)
			(layer "F.SilkS")
		)
		(fp_line
			(start -1.143 -0.5588)
			(end -1.143 0.5588)
			(stroke
				(width 0.1)
				(type default)
			)
			(layer "F.SilkS")
		)
		(fp_line
			(start 1.143 0.5588)
			(end 1.143 -0.5588)
			(stroke
				(width 0.1)
				(type default)
			)
			(layer "F.SilkS")
		)
		(fp_line
			(start -1.143 0.5588)
			(end 1.143 0.5588)
			(stroke
				(width 0.1)
				(type default)
			)
			(layer "F.SilkS")
		)
		(fp_poly
			(pts
				(xy -1.143 0.5588) (xy 1.143 0.5588) (xy 1.143 -0.5588) (xy -1.143 -0.5588)
			)
			(stroke
				(width 0)
				(type default)
			)
			(fill no)
			(layer "F.CrtYd")
		)
		(fp_line
			(start 0.508 -0.3048)
			(end -0.508 -0.3048)
			(stroke
				(width 0.1)
				(type default)
			)
			(layer "F.Fab")
		)
		(fp_line
			(start -0.508 -0.3048)
			(end -0.508 0.3048)
			(stroke
				(width 0.1)
				(type default)
			)
			(layer "F.Fab")
		)
		(fp_line
			(start 0.508 0.3048)
			(end 0.508 -0.3048)
			(stroke
				(width 0.1)
				(type default)
			)
			(layer "F.Fab")
		)
		(fp_line
			(start -0.508 0.3048)
			(end 0.508 0.3048)
			(stroke
				(width 0.1)
				(type default)
			)
			(layer "F.Fab")
		)
		(pad "1" smd rect
			(at -0.5334 0 90)
			(size 0.7112 0.6096)
			(layers "F.Cu" "F.Mask" "F.Paste")
			(net "FPGA_D01")
		)
		(pad "2" smd rect
			(at 0.5334 0 90)
			(size 0.7112 0.6096)
			(layers "F.Cu" "F.Mask" "F.Paste")
			(net "FPGA_FLASH_DQ1_MISO")
		)
		(zone
			(layer "F.Cu")
			(hatch none 0.5)
			(connect_pads
				(clearance 0)
			)
			(min_thickness 0.25)
			(keepout
				(tracks allowed)
				(vias not_allowed)
				(pads allowed)
				(copperpour not_allowed)
				(footprints allowed)
			)
			(placement
				(enabled no)
				(sheetname "")
			)
			(fill
				(thermal_gap 0.5)
				(thermal_bridge_width 0.5)
				(island_removal_mode 0)
			)
			(polygon
				(pts
					(xy 115.4938 -59.4868) (xy 115.4938 -59.6392) (xy 114.8842 -59.6392) (xy 114.8842 -59.4868)
				)
			)
		)
		(zone
			(layer "F.Cu")
			(hatch none 0.5)
			(connect_pads
				(clearance 0)
			)
			(min_thickness 0.25)
			(keepout
				(tracks not_allowed)
				(vias allowed)
				(pads allowed)
				(copperpour not_allowed)
				(footprints allowed)
			)
			(placement
				(enabled no)
				(sheetname "")
			)
			(fill
				(thermal_gap 0.5)
				(thermal_bridge_width 0.5)
				(island_removal_mode 0)
			)
			(polygon
				(pts
					(xy 115.4938 -59.4868) (xy 115.4938 -59.6392) (xy 114.8842 -59.6392) (xy 114.8842 -59.4868)
				)
			)
		)
	)
	(footprint ""
		(layer "F.Cu")
		(at 33.77438 -19.1262 180)
		(property "Reference" "R313"
			(at -3.05562 -0.75057 0)
			(unlocked yes)
			(layer "F.SilkS")
			(effects
				(font
					(size 0.7874 0.5842)
					(thickness 0.1524)
				)
			)
		)
		(property "Value" "VAL*"
			(at 0.02032 2.13233 180)
			(unlocked yes)
			(layer "F.Fab")
			(hide yes)
			(effects
				(font
					(size 0.7874 0.5842)
					(thickness 0.1524)
				)
			)
		)
		(property "Device Type" "RESISTOR-G155-100R0-J0,0OHM,-"
			(at 0.008382 1.210564 180)
			(unlocked yes)
			(layer "F.Fab")
			(hide yes)
			(effects
				(font
					(size 0.7874 0.5842)
					(thickness 0.1524)
				)
			)
		)
		(property "User Part Number" "PARTNUM*"
			(at 0.02032 4.024884 180)
			(unlocked yes)
			(layer "Cmts.User")
			(hide yes)
			(effects
				(font
					(size 0.7874 0.5842)
					(thickness 0.1524)
				)
			)
		)
		(property "Tolerance" "TOL*"
			(at 0.044704 3.05435 180)
			(unlocked yes)
			(layer "Cmts.User")
			(hide yes)
			(effects
				(font
					(size 0.7874 0.5842)
					(thickness 0.1524)
				)
			)
		)
		(duplicate_pad_numbers_are_jumpers no)
		(fp_line
			(start 1.143 0.5588)
			(end 1.143 -0.5588)
			(stroke
				(width 0.1)
				(type default)
			)
			(layer "F.SilkS")
		)
		(fp_line
			(start 1.143 -0.5588)
			(end -1.143 -0.5588)
			(stroke
				(width 0.1)
				(type default)
			)
			(layer "F.SilkS")
		)
		(fp_line
			(start -1.143 0.5588)
			(end 1.143 0.5588)
			(stroke
				(width 0.1)
				(type default)
			)
			(layer "F.SilkS")
		)
		(fp_line
			(start -1.143 -0.5588)
			(end -1.143 0.5588)
			(stroke
				(width 0.1)
				(type default)
			)
			(layer "F.SilkS")
		)
		(fp_poly
			(pts
				(xy -1.143 0.5588) (xy 1.143 0.5588) (xy 1.143 -0.5588) (xy -1.143 -0.5588)
			)
			(stroke
				(width 0)
				(type default)
			)
			(fill no)
			(layer "F.CrtYd")
		)
		(fp_line
			(start 0.508 0.3048)
			(end 0.508 -0.3048)
			(stroke
				(width 0.1)
				(type default)
			)
			(layer "F.Fab")
		)
		(fp_line
			(start 0.508 -0.3048)
			(end -0.508 -0.3048)
			(stroke
				(width 0.1)
				(type default)
			)
			(layer "F.Fab")
		)
		(fp_line
			(start -0.508 0.3048)
			(end 0.508 0.3048)
			(stroke
				(width 0.1)
				(type default)
			)
			(layer "F.Fab")
		)
		(fp_line
			(start -0.508 -0.3048)
			(end -0.508 0.3048)
			(stroke
				(width 0.1)
				(type default)
			)
			(layer "F.Fab")
		)
		(pad "1" smd rect
			(at -0.5334 0 180)
			(size 0.7112 0.6096)
			(layers "F.Cu" "F.Mask" "F.Paste")
			(net "RGB_LED_I2C_SCL")
		)
		(pad "2" smd rect
			(at 0.5334 0 180)
			(size 0.7112 0.6096)
			(layers "F.Cu" "F.Mask" "F.Paste")
			(net "EEPROM_SCL")
		)
		(zone
			(layer "F.Cu")
			(hatch none 0.5)
			(connect_pads
				(clearance 0)
			)
			(min_thickness 0.25)
			(keepout
				(tracks not_allowed)
				(vias allowed)
				(pads allowed)
				(copperpour not_allowed)
				(footprints allowed)
			)
			(placement
				(enabled no)
				(sheetname "")
			)
			(fill
				(thermal_gap 0.5)
				(thermal_bridge_width 0.5)
				(island_removal_mode 0)
			)
			(polygon
				(pts
					(xy 33.85058 -19.431) (xy 33.69818 -19.431) (xy 33.69818 -18.8214) (xy 33.85058 -18.8214)
				)
			)
		)
		(zone
			(layer "F.Cu")
			(hatch none 0.5)
			(connect_pads
				(clearance 0)
			)
			(min_thickness 0.25)
			(keepout
				(tracks allowed)
				(vias not_allowed)
				(pads allowed)
				(copperpour not_allowed)
				(footprints allowed)
			)
			(placement
				(enabled no)
				(sheetname "")
			)
			(fill
				(thermal_gap 0.5)
				(thermal_bridge_width 0.5)
				(island_removal_mode 0)
			)
			(polygon
				(pts
					(xy 33.85058 -19.431) (xy 33.69818 -19.431) (xy 33.69818 -18.8214) (xy 33.85058 -18.8214)
				)
			)
		)
	)
	(footprint ""
		(layer "F.Cu")
		(at 19.468338 -45.593 180)
		(property "Reference" "R400"
			(at -3.518662 0.08763 0)
			(unlocked yes)
			(layer "F.SilkS")
			(effects
				(font
					(size 0.7874 0.5842)
					(thickness 0.1524)
				)
			)
		)
		(property "Value" "VAL*"
			(at 0.02032 2.13233 180)
			(unlocked yes)
			(layer "F.Fab")
			(hide yes)
			(effects
				(font
					(size 0.7874 0.5842)
					(thickness 0.1524)
				)
			)
		)
		(property "Device Type" "RESISTOR-G155-11000-01,100OHM,A"
			(at 0.008382 1.210564 180)
			(unlocked yes)
			(layer "F.Fab")
			(hide yes)
			(effects
				(font
					(size 0.7874 0.5842)
					(thickness 0.1524)
				)
			)
		)
		(property "User Part Number" "PARTNUM*"
			(at 0.02032 4.024884 180)
			(unlocked yes)
			(layer "Cmts.User")
			(hide yes)
			(effects
				(font
					(size 0.7874 0.5842)
					(thickness 0.1524)
				)
			)
		)
		(property "Tolerance" "TOL*"
			(at 0.044704 3.05435 180)
			(unlocked yes)
			(layer "Cmts.User")
			(hide yes)
			(effects
				(font
					(size 0.7874 0.5842)
					(thickness 0.1524)
				)
			)
		)
		(duplicate_pad_numbers_are_jumpers no)
		(fp_line
			(start 1.143 0.5588)
			(end 1.143 -0.5588)
			(stroke
				(width 0.1)
				(type default)
			)
			(layer "F.SilkS")
		)
		(fp_line
			(start 1.143 -0.5588)
			(end -1.143 -0.5588)
			(stroke
				(width 0.1)
				(type default)
			)
			(layer "F.SilkS")
		)
		(fp_line
			(start -1.143 0.5588)
			(end 1.143 0.5588)
			(stroke
				(width 0.1)
				(type default)
			)
			(layer "F.SilkS")
		)
		(fp_line
			(start -1.143 -0.5588)
			(end -1.143 0.5588)
			(stroke
				(width 0.1)
				(type default)
			)
			(layer "F.SilkS")
		)
		(fp_poly
			(pts
				(xy -1.143 0.5588) (xy 1.143 0.5588) (xy 1.143 -0.5588) (xy -1.143 -0.5588)
			)
			(stroke
				(width 0)
				(type default)
			)
			(fill no)
			(layer "F.CrtYd")
		)
		(fp_line
			(start 0.508 0.3048)
			(end 0.508 -0.3048)
			(stroke
				(width 0.1)
				(type default)
			)
			(layer "F.Fab")
		)
		(fp_line
			(start 0.508 -0.3048)
			(end -0.508 -0.3048)
			(stroke
				(width 0.1)
				(type default)
			)
			(layer "F.Fab")
		)
		(fp_line
			(start -0.508 0.3048)
			(end 0.508 0.3048)
			(stroke
				(width 0.1)
				(type default)
			)
			(layer "F.Fab")
		)
		(fp_line
			(start -0.508 -0.3048)
			(end -0.508 0.3048)
			(stroke
				(width 0.1)
				(type default)
			)
			(layer "F.Fab")
		)
		(pad "1" smd rect
			(at -0.5334 0 180)
			(size 0.7112 0.6096)
			(layers "F.Cu" "F.Mask" "F.Paste")
			(net "FPGA_OUT_SMA4_LED_BLUE_N")
		)
		(pad "2" smd rect
			(at 0.5334 0 180)
			(size 0.7112 0.6096)
			(layers "F.Cu" "F.Mask" "F.Paste")
			(net "UNNAMED_14_LED4PV14_I268_1")
		)
		(zone
			(layer "F.Cu")
			(hatch none 0.5)
			(connect_pads
				(clearance 0)
			)
			(min_thickness 0.25)
			(keepout
				(tracks not_allowed)
				(vias allowed)
				(pads allowed)
				(copperpour not_allowed)
				(footprints allowed)
			)
			(placement
				(enabled no)
				(sheetname "")
			)
			(fill
				(thermal_gap 0.5)
				(thermal_bridge_width 0.5)
				(island_removal_mode 0)
			)
			(polygon
				(pts
					(xy 19.544538 -45.8978) (xy 19.392138 -45.8978) (xy 19.392138 -45.2882) (xy 19.544538 -45.2882)
				)
			)
		)
		(zone
			(layer "F.Cu")
			(hatch none 0.5)
			(connect_pads
				(clearance 0)
			)
			(min_thickness 0.25)
			(keepout
				(tracks allowed)
				(vias not_allowed)
				(pads allowed)
				(copperpour not_allowed)
				(footprints allowed)
			)
			(placement
				(enabled no)
				(sheetname "")
			)
			(fill
				(thermal_gap 0.5)
				(thermal_bridge_width 0.5)
				(island_removal_mode 0)
			)
			(polygon
				(pts
					(xy 19.544538 -45.8978) (xy 19.392138 -45.8978) (xy 19.392138 -45.2882) (xy 19.544538 -45.2882)
				)
			)
		)
	)
	(footprint ""
		(layer "F.Cu")
		(at 20.8534 -59.3598 90)
		(property "Reference" "U32"
			(at 0.0762 2.68097 90)
			(unlocked yes)
			(layer "F.SilkS")
			(effects
				(font
					(size 0.7874 0.5842)
					(thickness 0.1524)
				)
			)
		)
		(property "Value" ""
			(at 0 0 90)
			(layer "F.Fab")
			(effects
				(font
					(size 1.27 1.27)
				)
			)
		)
		(property "Device Type" "PCA9508DP_TSSOP8-G223-10278-01"
			(at -0.03175 2.55651 90)
			(unlocked yes)
			(layer "F.Fab")
			(hide yes)
			(effects
				(font
					(size 0.7874 0.5842)
					(thickness 0.1524)
				)
			)
		)
		(property "User Part Number" "PARTNUM*"
			(at -0.037592 3.488182 90)
			(unlocked yes)
			(layer "Cmts.User")
			(hide yes)
			(effects
				(font
					(size 0.7874 0.5842)
					(thickness 0.1524)
				)
			)
		)
		(duplicate_pad_numbers_are_jumpers no)
		(fp_line
			(start 1.778 -1.778)
			(end -1.778 -1.778)
			(stroke
				(width 0.1)
				(type default)
			)
			(layer "F.SilkS")
		)
		(fp_line
			(start -1.778 -1.778)
			(end -1.778 -1.45796)
			(stroke
				(width 0.1)
				(type default)
			)
			(layer "F.SilkS")
		)
		(fp_line
			(start 3.3147 -1.45796)
			(end 1.778 -1.45796)
			(stroke
				(width 0.1)
				(type default)
			)
			(layer "F.SilkS")
		)
		(fp_line
			(start 1.778 -1.45796)
			(end 1.778 -1.778)
			(stroke
				(width 0.1)
				(type default)
			)
			(layer "F.SilkS")
		)
		(fp_line
			(start -1.778 -1.45796)
			(end -3.3147 -1.45796)
			(stroke
				(width 0.1)
				(type default)
			)
			(layer "F.SilkS")
		)
		(fp_line
			(start -3.3147 -1.45796)
			(end -3.3147 1.45796)
			(stroke
				(width 0.1)
				(type default)
			)
			(layer "F.SilkS")
		)
		(fp_line
			(start 3.3147 1.45796)
			(end 3.3147 -1.45796)
			(stroke
				(width 0.1)
				(type default)
			)
			(layer "F.SilkS")
		)
		(fp_line
			(start 1.778 1.45796)
			(end 3.3147 1.45796)
			(stroke
				(width 0.1)
				(type default)
			)
			(layer "F.SilkS")
		)
		(fp_line
			(start -1.778 1.45796)
			(end -1.778 1.778)
			(stroke
				(width 0.1)
				(type default)
			)
			(layer "F.SilkS")
		)
		(fp_line
			(start -3.3147 1.45796)
			(end -1.778 1.45796)
			(stroke
				(width 0.1)
				(type default)
			)
			(layer "F.SilkS")
		)
		(fp_line
			(start 1.778 1.778)
			(end 1.778 1.45796)
			(stroke
				(width 0.1)
				(type default)
			)
			(layer "F.SilkS")
		)
		(fp_line
			(start -1.778 1.778)
			(end 1.778 1.778)
			(stroke
				(width 0.1)
				(type default)
			)
			(layer "F.SilkS")
		)
		(fp_poly
			(pts
				(arc
					(start -3.3528 -1.6764)
					(mid -3.3528 -2.4384)
					(end -3.3528 -1.6764)
				)
			)
			(stroke
				(width 0)
				(type default)
			)
			(fill yes)
			(layer "F.SilkS")
		)
		(fp_poly
			(pts
				(xy -3.5687 -2.032) (xy -3.5687 2.032) (xy 3.5687 2.032) (xy 3.5687 -2.032)
			)
			(stroke
				(width 0)
				(type default)
			)
			(fill no)
			(layer "F.CrtYd")
		)
		(fp_line
			(start 1.524 -1.524)
			(end 1.524 1.524)
			(stroke
				(width 0.1)
				(type default)
			)
			(layer "F.Fab")
		)
		(fp_line
			(start -1.524 -1.524)
			(end 1.524 -1.524)
			(stroke
				(width 0.1)
				(type default)
			)
			(layer "F.Fab")
		)
		(fp_line
			(start 1.524 1.524)
			(end -1.524 1.524)
			(stroke
				(width 0.1)
				(type default)
			)
			(layer "F.Fab")
		)
		(fp_line
			(start -1.524 1.524)
			(end -1.524 -1.524)
			(stroke
				(width 0.1)
				(type default)
			)
			(layer "F.Fab")
		)
		(fp_poly
			(pts
				(arc
					(start -0.9906 -0.5588)
					(mid -0.9906 -1.3208)
					(end -0.9906 -0.5588)
				)
			)
			(stroke
				(width 0)
				(type default)
			)
			(fill yes)
			(layer "F.Fab")
		)
		(fp_text user "8"
			(at 3.72745 -2.0574 0)
			(unlocked yes)
			(layer "F.SilkS")
			(effects
				(font
					(size 0.635 0.4064)
					(thickness 0.1524)
				)
			)
		)
		(fp_text user "4"
			(at -2.95275 2.1336 0)
			(unlocked yes)
			(layer "F.SilkS")
			(effects
				(font
					(size 0.635 0.4064)
					(thickness 0.1524)
				)
			)
		)
		(fp_text user "5"
			(at 2.96545 2.2606 0)
			(unlocked yes)
			(layer "F.SilkS")
			(effects
				(font
					(size 0.635 0.4064)
					(thickness 0.1524)
				)
			)
		)
		(fp_text user "8"
			(at 2.32283 -1.5494 0)
			(unlocked yes)
			(layer "F.Fab")
			(effects
				(font
					(size 0.7874 0.5842)
					(thickness 0.1524)
				)
			)
		)
		(fp_text user "4"
			(at -2.75717 1.4986 0)
			(unlocked yes)
			(layer "F.Fab")
			(effects
				(font
					(size 0.7874 0.5842)
					(thickness 0.1524)
				)
			)
		)
		(fp_text user "5"
			(at 2.32283 1.6256 0)
			(unlocked yes)
			(layer "F.Fab")
			(effects
				(font
					(size 0.7874 0.5842)
					(thickness 0.1524)
				)
			)
		)
		(pad "1" smd rect
			(at -2.2987 -0.97536 180)
			(size 0.4572 1.524)
			(layers "F.Cu" "F.Mask" "F.Paste")
			(net "XP1R8V_ICP10100")
		)
		(pad "2" smd rect
			(at -2.2987 -0.32512 180)
			(size 0.4572 1.524)
			(layers "F.Cu" "F.Mask" "F.Paste")
			(net "BF_ICP10100_I2C_SCL")
		)
		(pad "3" smd rect
			(at -2.2987 0.32512 180)
			(size 0.4572 1.524)
			(layers "F.Cu" "F.Mask" "F.Paste")
			(net "BF_ICP10100_I2C_SDA")
		)
		(pad "4" smd rect
			(at -2.2987 0.97536 180)
			(size 0.4572 1.524)
			(layers "F.Cu" "F.Mask" "F.Paste")
			(net "SG")
		)
		(pad "5" smd rect
			(at 2.2987 0.97536 180)
			(size 0.4572 1.524)
			(layers "F.Cu" "F.Mask" "F.Paste")
			(net "UNNAMED_8_PCA9508DPTSSOP8_I51_E")
		)
		(pad "6" smd rect
			(at 2.2987 0.32512 180)
			(size 0.4572 1.524)
			(layers "F.Cu" "F.Mask" "F.Paste")
			(net "ICP10100_I2C_SDA")
		)
		(pad "7" smd rect
			(at 2.2987 -0.32512 180)
			(size 0.4572 1.524)
			(layers "F.Cu" "F.Mask" "F.Paste")
			(net "ICP10100_I2C_SCL")
		)
		(pad "8" smd rect
			(at 2.2987 -0.97536 180)
			(size 0.4572 1.524)
			(layers "F.Cu" "F.Mask" "F.Paste")
			(net "XP3R3V")
		)
	)
)
